(kicad_pcb
	(version 20260206)
	(generator "pcbnew")
	(generator_version "10.0")
	(general
		(thickness 1.6)
		(legacy_teardrops no)
	)
	(paper "A4")
	(title_block
		(title "9052_F0T_PDB_Converter_Brick_F_V03_1208_1600_OCP.brd")
		(comment 1 "Grand Teton / footprints 319-324 of 578")
	)
	(layers
		(0 "F.Cu" signal "TOP")
		(4 "In1.Cu" signal "GND")
		(6 "In2.Cu" signal "IN1")
		(8 "In3.Cu" signal "GND1")
		(10 "In4.Cu" signal "VCC")
		(12 "In5.Cu" signal "VCC1")
		(14 "In6.Cu" signal "GND2")
		(16 "In7.Cu" signal "IN2")
		(18 "In8.Cu" signal "GND3")
		(2 "B.Cu" signal "BOTTOM")
		(9 "F.Adhes" user "F.Adhesive")
		(11 "B.Adhes" user "B.Adhesive")
		(13 "F.Paste" user "Package Geometry/Pastemask Top")
		(15 "B.Paste" user "Package Geometry/Pastemask Bottom")
		(5 "F.SilkS" user "Ref Des/Silkscreen Top")
		(7 "B.SilkS" user "Ref Des/Silkscreen Bottom")
		(1 "F.Mask" user "Board Geometry/Soldermask Top")
		(3 "B.Mask" user "Board Geometry/Soldermask Bottom")
		(17 "Dwgs.User" user "User.Drawings")
		(19 "Cmts.User" user "User.Comments")
		(21 "Eco1.User" user "User.Eco1")
		(23 "Eco2.User" user "User.Eco2")
		(25 "Edge.Cuts" user "Board Geometry/Outline")
		(27 "Margin" user)
		(31 "F.CrtYd" user "Package Geometry/Place Bound Top")
		(29 "B.CrtYd" user "Package Geometry/Place Bound Bottom")
		(35 "F.Fab" user "Ref Des/Assembly Top")
		(33 "B.Fab" user "Ref Des/Assembly Bottom")
	)
	(footprint ""
		(layer "B.Cu")
		(at 54.483 -78.613)
		(property "Reference" "R181"
			(at 0 0 0)
			(layer "B.SilkS")
			(hide yes)
			(effects
				(font
					(size 1.27 1.27)
				)
				(justify mirror)
			)
		)
		(property "Value" ""
			(at 0 0 0)
			(layer "B.Fab")
			(effects
				(font
					(size 1.27 1.27)
				)
				(justify mirror)
			)
		)
		(duplicate_pad_numbers_are_jumpers no)
		(fp_line
			(start -0.7874 -0.4064)
			(end -0.7874 0.4064)
			(stroke
				(width 0.1524)
				(type default)
			)
			(layer "B.SilkS")
		)
		(fp_line
			(start -0.7874 0.4064)
			(end 0.7874 0.4064)
			(stroke
				(width 0.1524)
				(type default)
			)
			(layer "B.SilkS")
		)
		(fp_line
			(start 0.7874 -0.4064)
			(end -0.7874 -0.4064)
			(stroke
				(width 0.1524)
				(type default)
			)
			(layer "B.SilkS")
		)
		(fp_line
			(start 0.7874 0.4064)
			(end 0.7874 -0.4064)
			(stroke
				(width 0.1524)
				(type default)
			)
			(layer "B.SilkS")
		)
		(fp_line
			(start -0.67945 -0.3048)
			(end -0.67945 0.3048)
			(stroke
				(width 0.1)
				(type default)
			)
			(layer "B.Fab")
		)
		(fp_line
			(start -0.67945 0.3048)
			(end -0.120396 0.3048)
			(stroke
				(width 0.1)
				(type default)
			)
			(layer "B.Fab")
		)
		(fp_line
			(start -0.12065 -0.3048)
			(end -0.67945 -0.3048)
			(stroke
				(width 0.1)
				(type default)
			)
			(layer "B.Fab")
		)
		(fp_line
			(start -0.12065 -0.2794)
			(end -0.12065 -0.3048)
			(stroke
				(width 0.1)
				(type default)
			)
			(layer "B.Fab")
		)
		(fp_line
			(start -0.120396 0.2794)
			(end 0.12065 0.2794)
			(stroke
				(width 0.1)
				(type default)
			)
			(layer "B.Fab")
		)
		(fp_line
			(start -0.120396 0.3048)
			(end -0.120396 0.2794)
			(stroke
				(width 0.1)
				(type default)
			)
			(layer "B.Fab")
		)
		(fp_line
			(start 0.12065 -0.305054)
			(end 0.12065 -0.2794)
			(stroke
				(width 0.1)
				(type default)
			)
			(layer "B.Fab")
		)
		(fp_line
			(start 0.12065 -0.2794)
			(end -0.12065 -0.2794)
			(stroke
				(width 0.1)
				(type default)
			)
			(layer "B.Fab")
		)
		(fp_line
			(start 0.12065 0.2794)
			(end 0.12065 0.3048)
			(stroke
				(width 0.1)
				(type default)
			)
			(layer "B.Fab")
		)
		(fp_line
			(start 0.12065 0.3048)
			(end 0.67945 0.3048)
			(stroke
				(width 0.1)
				(type default)
			)
			(layer "B.Fab")
		)
		(fp_line
			(start 0.67945 -0.305054)
			(end 0.12065 -0.305054)
			(stroke
				(width 0.1)
				(type default)
			)
			(layer "B.Fab")
		)
		(fp_line
			(start 0.67945 0.3048)
			(end 0.67945 -0.305054)
			(stroke
				(width 0.1)
				(type default)
			)
			(layer "B.Fab")
		)
		(pad "1" smd circle
			(at 0.40005 0 180)
			(size 0 0)
			(layers "B.Cu" "B.Mask" "B.Paste")
			(net "P3V3_AUX")
		)
		(pad "2" smd circle
			(at -0.40005 0 180)
			(size 0 0)
			(layers "B.Cu" "B.Mask" "B.Paste")
			(net "SMB_P52V_VPDB_SDA")
		)
	)
	(footprint ""
		(layer "B.Cu")
		(at 229.87 -87.757 180)
		(property "Reference" "U20"
			(at 2.43967 -1.016 270)
			(unlocked yes)
			(layer "B.SilkS")
			(effects
				(font
					(size 0.7874 0.5842)
					(thickness 0.1524)
				)
				(justify left mirror)
			)
		)
		(property "Value" ""
			(at 0 0 0)
			(layer "B.Fab")
			(effects
				(font
					(size 1.27 1.27)
				)
				(justify mirror)
			)
		)
		(duplicate_pad_numbers_are_jumpers no)
		(fp_line
			(start 1.603248 1.500124)
			(end 1.603248 -1.500124)
			(stroke
				(width 0.1524)
				(type default)
			)
			(layer "B.SilkS")
		)
		(fp_line
			(start 1.603248 -1.500124)
			(end -1.603248 -1.500124)
			(stroke
				(width 0.1524)
				(type default)
			)
			(layer "B.SilkS")
		)
		(fp_line
			(start -1.603248 1.500124)
			(end 1.603248 1.500124)
			(stroke
				(width 0.1524)
				(type default)
			)
			(layer "B.SilkS")
		)
		(fp_line
			(start -1.603248 -1.500124)
			(end -1.603248 1.500124)
			(stroke
				(width 0.1524)
				(type default)
			)
			(layer "B.SilkS")
		)
		(fp_line
			(start 1.249934 1.169924)
			(end 0.700024 1.169924)
			(stroke
				(width 0.1)
				(type default)
			)
			(layer "B.Fab")
		)
		(fp_line
			(start 1.249934 0.729996)
			(end 1.249934 1.169924)
			(stroke
				(width 0.1)
				(type default)
			)
			(layer "B.Fab")
		)
		(fp_line
			(start 1.249934 -0.729996)
			(end 0.6985 -0.729996)
			(stroke
				(width 0.1)
				(type default)
			)
			(layer "B.Fab")
		)
		(fp_line
			(start 1.249934 -1.169924)
			(end 1.249934 -0.729996)
			(stroke
				(width 0.1)
				(type default)
			)
			(layer "B.Fab")
		)
		(fp_line
			(start 0.700024 1.500124)
			(end -0.700024 1.500124)
			(stroke
				(width 0.1)
				(type default)
			)
			(layer "B.Fab")
		)
		(fp_line
			(start 0.700024 1.169924)
			(end 0.700024 1.500124)
			(stroke
				(width 0.1)
				(type default)
			)
			(layer "B.Fab")
		)
		(fp_line
			(start 0.700024 -1.169924)
			(end 1.249934 -1.169924)
			(stroke
				(width 0.1)
				(type default)
			)
			(layer "B.Fab")
		)
		(fp_line
			(start 0.700024 -1.500124)
			(end 0.700024 -1.169924)
			(stroke
				(width 0.1)
				(type default)
			)
			(layer "B.Fab")
		)
		(fp_line
			(start 0.6985 0.729996)
			(end 1.249934 0.729996)
			(stroke
				(width 0.1)
				(type default)
			)
			(layer "B.Fab")
		)
		(fp_line
			(start 0.6985 -0.729996)
			(end 0.6985 0.729996)
			(stroke
				(width 0.1)
				(type default)
			)
			(layer "B.Fab")
		)
		(fp_line
			(start -0.700024 1.500124)
			(end -0.700024 0.219964)
			(stroke
				(width 0.1)
				(type default)
			)
			(layer "B.Fab")
		)
		(fp_line
			(start -0.700024 0.219964)
			(end -1.249934 0.219964)
			(stroke
				(width 0.1)
				(type default)
			)
			(layer "B.Fab")
		)
		(fp_line
			(start -0.700024 -0.219964)
			(end -0.700024 -1.500124)
			(stroke
				(width 0.1)
				(type default)
			)
			(layer "B.Fab")
		)
		(fp_line
			(start -0.700024 -1.500124)
			(end 0.700024 -1.500124)
			(stroke
				(width 0.1)
				(type default)
			)
			(layer "B.Fab")
		)
		(fp_line
			(start -1.249934 0.219964)
			(end -1.249934 -0.219964)
			(stroke
				(width 0.1)
				(type default)
			)
			(layer "B.Fab")
		)
		(fp_line
			(start -1.249934 -0.219964)
			(end -0.700024 -0.219964)
			(stroke
				(width 0.1)
				(type default)
			)
			(layer "B.Fab")
		)
		(fp_rect
			(start 0.700024 -1.500124)
			(end -0.700024 1.500124)
			(stroke
				(width 0)
				(type default)
			)
			(fill no)
			(layer "B.Fab")
		)
		(pad "D" smd rect
			(at -0.999998 0 90)
			(size 0.8128 0.9144)
			(layers "B.Cu" "B.Mask" "B.Paste")
			(net "PWRGD_P3V3_AUX_MB_BUF_N")
		)
		(pad "G" smd rect
			(at 0.999998 -0.94996 90)
			(size 0.8128 0.9144)
			(layers "B.Cu" "B.Mask" "B.Paste")
			(net "PWRGD_P3V3_AUX_MB_BUF")
		)
		(pad "S" smd rect
			(at 0.999998 0.94996 90)
			(size 0.8128 0.9144)
			(layers "B.Cu" "B.Mask" "B.Paste")
			(net "GND")
		)
	)
	(footprint ""
		(layer "B.Cu")
		(at 38.989 -88.011)
		(property "Reference" "R76"
			(at 0 0 0)
			(layer "B.SilkS")
			(hide yes)
			(effects
				(font
					(size 1.27 1.27)
				)
				(justify mirror)
			)
		)
		(property "Value" ""
			(at 0 0 0)
			(layer "B.Fab")
			(effects
				(font
					(size 1.27 1.27)
				)
				(justify mirror)
			)
		)
		(duplicate_pad_numbers_are_jumpers no)
		(fp_line
			(start -0.7874 -0.4064)
			(end -0.7874 0.4064)
			(stroke
				(width 0.1524)
				(type default)
			)
			(layer "B.SilkS")
		)
		(fp_line
			(start -0.7874 0.4064)
			(end 0.7874 0.4064)
			(stroke
				(width 0.1524)
				(type default)
			)
			(layer "B.SilkS")
		)
		(fp_line
			(start 0.7874 -0.4064)
			(end -0.7874 -0.4064)
			(stroke
				(width 0.1524)
				(type default)
			)
			(layer "B.SilkS")
		)
		(fp_line
			(start 0.7874 0.4064)
			(end 0.7874 -0.4064)
			(stroke
				(width 0.1524)
				(type default)
			)
			(layer "B.SilkS")
		)
		(fp_line
			(start -0.67945 -0.3048)
			(end -0.67945 0.3048)
			(stroke
				(width 0.1)
				(type default)
			)
			(layer "B.Fab")
		)
		(fp_line
			(start -0.67945 0.3048)
			(end -0.120396 0.3048)
			(stroke
				(width 0.1)
				(type default)
			)
			(layer "B.Fab")
		)
		(fp_line
			(start -0.12065 -0.3048)
			(end -0.67945 -0.3048)
			(stroke
				(width 0.1)
				(type default)
			)
			(layer "B.Fab")
		)
		(fp_line
			(start -0.12065 -0.2794)
			(end -0.12065 -0.3048)
			(stroke
				(width 0.1)
				(type default)
			)
			(layer "B.Fab")
		)
		(fp_line
			(start -0.120396 0.2794)
			(end 0.12065 0.2794)
			(stroke
				(width 0.1)
				(type default)
			)
			(layer "B.Fab")
		)
		(fp_line
			(start -0.120396 0.3048)
			(end -0.120396 0.2794)
			(stroke
				(width 0.1)
				(type default)
			)
			(layer "B.Fab")
		)
		(fp_line
			(start 0.12065 -0.305054)
			(end 0.12065 -0.2794)
			(stroke
				(width 0.1)
				(type default)
			)
			(layer "B.Fab")
		)
		(fp_line
			(start 0.12065 -0.2794)
			(end -0.12065 -0.2794)
			(stroke
				(width 0.1)
				(type default)
			)
			(layer "B.Fab")
		)
		(fp_line
			(start 0.12065 0.2794)
			(end 0.12065 0.3048)
			(stroke
				(width 0.1)
				(type default)
			)
			(layer "B.Fab")
		)
		(fp_line
			(start 0.12065 0.3048)
			(end 0.67945 0.3048)
			(stroke
				(width 0.1)
				(type default)
			)
			(layer "B.Fab")
		)
		(fp_line
			(start 0.67945 -0.305054)
			(end 0.12065 -0.305054)
			(stroke
				(width 0.1)
				(type default)
			)
			(layer "B.Fab")
		)
		(fp_line
			(start 0.67945 0.3048)
			(end 0.67945 -0.305054)
			(stroke
				(width 0.1)
				(type default)
			)
			(layer "B.Fab")
		)
		(pad "1" smd circle
			(at 0.40005 0 180)
			(size 0 0)
			(layers "B.Cu" "B.Mask" "B.Paste")
			(net "SMB_HPDB_MISC_SCL")
		)
		(pad "2" smd circle
			(at -0.40005 0 180)
			(size 0 0)
			(layers "B.Cu" "B.Mask" "B.Paste")
			(net "SMB_HPDB_MISC_R_SCL")
		)
	)
	(footprint ""
		(layer "B.Cu")
		(at 205.74 -90.678 180)
		(property "Reference" "R103"
			(at 0 0 0)
			(layer "B.SilkS")
			(hide yes)
			(effects
				(font
					(size 1.27 1.27)
				)
				(justify mirror)
			)
		)
		(property "Value" ""
			(at 0 0 0)
			(layer "B.Fab")
			(effects
				(font
					(size 1.27 1.27)
				)
				(justify mirror)
			)
		)
		(duplicate_pad_numbers_are_jumpers no)
		(fp_line
			(start 0.7874 0.4064)
			(end 0.7874 -0.4064)
			(stroke
				(width 0.1524)
				(type default)
			)
			(layer "B.SilkS")
		)
		(fp_line
			(start 0.7874 -0.4064)
			(end -0.7874 -0.4064)
			(stroke
				(width 0.1524)
				(type default)
			)
			(layer "B.SilkS")
		)
		(fp_line
			(start -0.7874 0.4064)
			(end 0.7874 0.4064)
			(stroke
				(width 0.1524)
				(type default)
			)
			(layer "B.SilkS")
		)
		(fp_line
			(start -0.7874 -0.4064)
			(end -0.7874 0.4064)
			(stroke
				(width 0.1524)
				(type default)
			)
			(layer "B.SilkS")
		)
		(fp_line
			(start 0.67945 0.3048)
			(end 0.67945 -0.305054)
			(stroke
				(width 0.1)
				(type default)
			)
			(layer "B.Fab")
		)
		(fp_line
			(start 0.67945 -0.305054)
			(end 0.12065 -0.305054)
			(stroke
				(width 0.1)
				(type default)
			)
			(layer "B.Fab")
		)
		(fp_line
			(start 0.12065 0.3048)
			(end 0.67945 0.3048)
			(stroke
				(width 0.1)
				(type default)
			)
			(layer "B.Fab")
		)
		(fp_line
			(start 0.12065 0.2794)
			(end 0.12065 0.3048)
			(stroke
				(width 0.1)
				(type default)
			)
			(layer "B.Fab")
		)
		(fp_line
			(start 0.12065 -0.2794)
			(end -0.12065 -0.2794)
			(stroke
				(width 0.1)
				(type default)
			)
			(layer "B.Fab")
		)
		(fp_line
			(start 0.12065 -0.305054)
			(end 0.12065 -0.2794)
			(stroke
				(width 0.1)
				(type default)
			)
			(layer "B.Fab")
		)
		(fp_line
			(start -0.120396 0.3048)
			(end -0.120396 0.2794)
			(stroke
				(width 0.1)
				(type default)
			)
			(layer "B.Fab")
		)
		(fp_line
			(start -0.120396 0.2794)
			(end 0.12065 0.2794)
			(stroke
				(width 0.1)
				(type default)
			)
			(layer "B.Fab")
		)
		(fp_line
			(start -0.12065 -0.2794)
			(end -0.12065 -0.3048)
			(stroke
				(width 0.1)
				(type default)
			)
			(layer "B.Fab")
		)
		(fp_line
			(start -0.12065 -0.3048)
			(end -0.67945 -0.3048)
			(stroke
				(width 0.1)
				(type default)
			)
			(layer "B.Fab")
		)
		(fp_line
			(start -0.67945 0.3048)
			(end -0.120396 0.3048)
			(stroke
				(width 0.1)
				(type default)
			)
			(layer "B.Fab")
		)
		(fp_line
			(start -0.67945 -0.3048)
			(end -0.67945 0.3048)
			(stroke
				(width 0.1)
				(type default)
			)
			(layer "B.Fab")
		)
		(pad "1" smd circle
			(at 0.40005 0)
			(size 0 0)
			(layers "B.Cu" "B.Mask" "B.Paste")
			(net "PCA9543_MISC_A1")
		)
		(pad "2" smd circle
			(at -0.40005 0)
			(size 0 0)
			(layers "B.Cu" "B.Mask" "B.Paste")
			(net "GND")
		)
	)
	(footprint ""
		(layer "B.Cu")
		(at 281.94 -36.449 -90)
		(property "Reference" "R152"
			(at 0 0 90)
			(layer "B.SilkS")
			(hide yes)
			(effects
				(font
					(size 1.27 1.27)
				)
				(justify mirror)
			)
		)
		(property "Value" ""
			(at 0 0 90)
			(layer "B.Fab")
			(effects
				(font
					(size 1.27 1.27)
				)
				(justify mirror)
			)
		)
		(duplicate_pad_numbers_are_jumpers no)
		(fp_line
			(start -0.7874 0.4064)
			(end 0.7874 0.4064)
			(stroke
				(width 0.1524)
				(type default)
			)
			(layer "B.SilkS")
		)
		(fp_line
			(start 0.7874 0.4064)
			(end 0.7874 -0.4064)
			(stroke
				(width 0.1524)
				(type default)
			)
			(layer "B.SilkS")
		)
		(fp_line
			(start -0.7874 -0.4064)
			(end -0.7874 0.4064)
			(stroke
				(width 0.1524)
				(type default)
			)
			(layer "B.SilkS")
		)
		(fp_line
			(start 0.7874 -0.4064)
			(end -0.7874 -0.4064)
			(stroke
				(width 0.1524)
				(type default)
			)
			(layer "B.SilkS")
		)
		(fp_line
			(start -0.67945 0.3048)
			(end -0.120396 0.3048)
			(stroke
				(width 0.1)
				(type default)
			)
			(layer "B.Fab")
		)
		(fp_line
			(start -0.120396 0.3048)
			(end -0.120396 0.2794)
			(stroke
				(width 0.1)
				(type default)
			)
			(layer "B.Fab")
		)
		(fp_line
			(start 0.12065 0.3048)
			(end 0.67945 0.3048)
			(stroke
				(width 0.1)
				(type default)
			)
			(layer "B.Fab")
		)
		(fp_line
			(start 0.67945 0.3048)
			(end 0.67945 -0.305054)
			(stroke
				(width 0.1)
				(type default)
			)
			(layer "B.Fab")
		)
		(fp_line
			(start -0.120396 0.2794)
			(end 0.12065 0.2794)
			(stroke
				(width 0.1)
				(type default)
			)
			(layer "B.Fab")
		)
		(fp_line
			(start 0.12065 0.2794)
			(end 0.12065 0.3048)
			(stroke
				(width 0.1)
				(type default)
			)
			(layer "B.Fab")
		)
		(fp_line
			(start -0.12065 -0.2794)
			(end -0.12065 -0.3048)
			(stroke
				(width 0.1)
				(type default)
			)
			(layer "B.Fab")
		)
		(fp_line
			(start 0.12065 -0.2794)
			(end -0.12065 -0.2794)
			(stroke
				(width 0.1)
				(type default)
			)
			(layer "B.Fab")
		)
		(fp_line
			(start -0.67945 -0.3048)
			(end -0.67945 0.3048)
			(stroke
				(width 0.1)
				(type default)
			)
			(layer "B.Fab")
		)
		(fp_line
			(start -0.12065 -0.3048)
			(end -0.67945 -0.3048)
			(stroke
				(width 0.1)
				(type default)
			)
			(layer "B.Fab")
		)
		(fp_line
			(start 0.12065 -0.305054)
			(end 0.12065 -0.2794)
			(stroke
				(width 0.1)
				(type default)
			)
			(layer "B.Fab")
		)
		(fp_line
			(start 0.67945 -0.305054)
			(end 0.12065 -0.305054)
			(stroke
				(width 0.1)
				(type default)
			)
			(layer "B.Fab")
		)
		(pad "1" smd circle
			(at 0.40005 0 90)
			(size 0 0)
			(layers "B.Cu" "B.Mask" "B.Paste")
			(net "P3V3_AUX")
		)
		(pad "2" smd circle
			(at -0.40005 0 90)
			(size 0 0)
			(layers "B.Cu" "B.Mask" "B.Paste")
			(net "P52V_HS1_GPO1")
		)
	)
	(footprint ""
		(layer "B.Cu")
		(at 231.013 -75.184 -90)
		(property "Reference" "R141"
			(at 0 0 90)
			(layer "B.SilkS")
			(hide yes)
			(effects
				(font
					(size 1.27 1.27)
				)
				(justify mirror)
			)
		)
		(property "Value" ""
			(at 0 0 90)
			(layer "B.Fab")
			(effects
				(font
					(size 1.27 1.27)
				)
				(justify mirror)
			)
		)
		(duplicate_pad_numbers_are_jumpers no)
		(fp_line
			(start -0.7874 0.4064)
			(end 0.7874 0.4064)
			(stroke
				(width 0.1524)
				(type default)
			)
			(layer "B.SilkS")
		)
		(fp_line
			(start 0.7874 0.4064)
			(end 0.7874 -0.4064)
			(stroke
				(width 0.1524)
				(type default)
			)
			(layer "B.SilkS")
		)
		(fp_line
			(start -0.7874 -0.4064)
			(end -0.7874 0.4064)
			(stroke
				(width 0.1524)
				(type default)
			)
			(layer "B.SilkS")
		)
		(fp_line
			(start 0.7874 -0.4064)
			(end -0.7874 -0.4064)
			(stroke
				(width 0.1524)
				(type default)
			)
			(layer "B.SilkS")
		)
		(fp_line
			(start -0.67945 0.3048)
			(end -0.120396 0.3048)
			(stroke
				(width 0.1)
				(type default)
			)
			(layer "B.Fab")
		)
		(fp_line
			(start -0.120396 0.3048)
			(end -0.120396 0.2794)
			(stroke
				(width 0.1)
				(type default)
			)
			(layer "B.Fab")
		)
		(fp_line
			(start 0.12065 0.3048)
			(end 0.67945 0.3048)
			(stroke
				(width 0.1)
				(type default)
			)
			(layer "B.Fab")
		)
		(fp_line
			(start 0.67945 0.3048)
			(end 0.67945 -0.305054)
			(stroke
				(width 0.1)
				(type default)
			)
			(layer "B.Fab")
		)
		(fp_line
			(start -0.120396 0.2794)
			(end 0.12065 0.2794)
			(stroke
				(width 0.1)
				(type default)
			)
			(layer "B.Fab")
		)
		(fp_line
			(start 0.12065 0.2794)
			(end 0.12065 0.3048)
			(stroke
				(width 0.1)
				(type default)
			)
			(layer "B.Fab")
		)
		(fp_line
			(start -0.12065 -0.2794)
			(end -0.12065 -0.3048)
			(stroke
				(width 0.1)
				(type default)
			)
			(layer "B.Fab")
		)
		(fp_line
			(start 0.12065 -0.2794)
			(end -0.12065 -0.2794)
			(stroke
				(width 0.1)
				(type default)
			)
			(layer "B.Fab")
		)
		(fp_line
			(start -0.67945 -0.3048)
			(end -0.67945 0.3048)
			(stroke
				(width 0.1)
				(type default)
			)
			(layer "B.Fab")
		)
		(fp_line
			(start -0.12065 -0.3048)
			(end -0.67945 -0.3048)
			(stroke
				(width 0.1)
				(type default)
			)
			(layer "B.Fab")
		)
		(fp_line
			(start 0.12065 -0.305054)
			(end 0.12065 -0.2794)
			(stroke
				(width 0.1)
				(type default)
			)
			(layer "B.Fab")
		)
		(fp_line
			(start 0.67945 -0.305054)
			(end 0.12065 -0.305054)
			(stroke
				(width 0.1)
				(type default)
			)
			(layer "B.Fab")
		)
		(pad "1" smd circle
			(at 0.40005 0 90)
			(size 0 0)
			(layers "B.Cu" "B.Mask" "B.Paste")
			(net "PWRGD_P3V3_AUX_MB")
		)
		(pad "2" smd circle
			(at -0.40005 0 90)
			(size 0 0)
			(layers "B.Cu" "B.Mask" "B.Paste")
			(net "PWRGD_P3V3_AUX_MB_R1")
		)
	)
)
